# BASEBOARD_FAB2 (Tioga Pass) — schematic netlist excerpt (pin names and nets, part order shuffled) for the footprints in the layout excerpt that follows; sources: Cadence DE-HDL packaged netlist, KiCad conversion of Wiwynn_Tioga_Pass_MB.brd

J4E1  SCONN120_H61426002  CONN  pkg SM  page 193
  IOA1  = PVCCMCP_CPU1
  IOA2  = PVCCMCP_CPU1
  IOA3  = PVCCMCP_CPU1
  IOA4  = VSENSE_PVCCMCP_CPU1_SKT_VSEN
  IOA5  = PVCCMCP_CPU1
  IOA6  = PVCCMCP_CPU1
  IOA7  = PVCCMCP_CPU1
  IOA8  = PVCCMCP_CPU1
  IOA9  = PVCCMCP_CPU1
  IOA10  = PVCCMCP_CPU1
  IOA11  = PVCCMCP_CPU1
  IOA12  = PVCCMCP_CPU1
  IOA13  = PVCCMCP_CPU1
  IOA14  = PVCCMCP_CPU1
  IOA15  = PVCCMCP_CPU1
  IOA16  = PVCCMCP_CPU1
  IOA17  = PVCCMCP_CPU1
  IOA18  = PVCCMCP_CPU1
  IOA19  = GND
  IOA20  = GND
  IOB1  = PVCCMCP_CPU1
  IOB2  = PVCCMCP_CPU1
  IOB3  = PVCCMCP_CPU1
  IOB4  = VSENSE_PVCCMCP_CPU1_SKT_VRTN
  IOB5  = PVCCMCP_CPU1
  IOB6  = PVCCMCP_CPU1
  IOB7  = PVCCMCP_CPU1
  IOB8  = PVCCMCP_CPU1
  IOB9  = PVCCMCP_CPU1
  IOB10  = PVCCMCP_CPU1
  IOB11  = PVCCMCP_CPU1
  IOB12  = PVCCMCP_CPU1
  IOB13  = PVCCMCP_CPU1
  IOB14  = PVCCMCP_CPU1
  IOB15  = PVCCMCP_CPU1
  IOB16  = PVCCMCP_CPU1
  IOB17  = PVCCMCP_CPU1
  IOB18  = PVCCMCP_CPU1
  IOB19  = GND
  IOB20  = GND
  IOC1  = PVCCMCP_CPU1
  IOC2  = PVCCMCP_CPU1
  IOC3  = PVCCMCP_CPU1
  IOC4  = PVCCMCP_CPU1
  IOC5  = PVCCMCP_CPU1
  IOC6  = PVCCMCP_CPU1
  IOC7  = PVCCMCP_CPU1
  IOC8  = PVCCMCP_CPU1
  IOC9  = PVCCMCP_CPU1
  IOC10  = PVCCMCP_CPU1
  IOC11  = PVCCMCP_CPU1
  IOC12  = PVCCMCP_CPU1
  IOC13  = PVCCMCP_CPU1
  IOC14  = PVCCMCP_CPU1
  IOC15  = PVCCMCP_CPU1
  IOC16  = PVCCMCP_CPU1
  IOC17  = PVCCMCP_CPU1
  IOC18  = PVCCMCP_CPU1
  IOC19  = GND
  IOC20  = GND
  IOD1  = VSENSE_P1V8MCP_CPU1_SKT_VSEN
  IOD2  = VSENSE_P1V8MCP_CPU1_SKT_VRTN
  IOD3  = P1V8_MCP_CPU1
  IOD4  = GND
  IOD5  = GND
  IOD6  = GND
  IOD7  = GND
  IOD8  = GND
  IOD9  = GND
  IOD10  = GND
  IOD11  = GND
  IOD12  = GND
  IOD13  = GND
  IOD14  = GND
  IOD15  = GND
  IOD16  = GND
  IOD17  = GND
  IOD18  = GND
  IOD19  = GND
  IOD20  = GND
  IOE1  = P1V8_MCP_CPU1
  IOE2  = P1V8_MCP_CPU1
  IOE3  = P1V8_MCP_CPU1
  IOE4  = GND
  IOE5  = CLK_322M_156M_CPU1_OSC_VRM_DP
  IOE6  = GND
  IOE7  = GND
  IOE8  = GND
  IOE9  = GND
  IOE10  = GND
  IOE11  = GND
  IOE12  = GND
  IOE13  = GND
  IOE14  = GND
  IOE15  = GND
  IOE16  = GND
  IOE17  = GND
  IOE18  = GND
  IOE19  = GND
  IOE20  = GND
  IOF1  = P1V8_MCP_CPU1
  IOF2  = P1V8_MCP_CPU1
  IOF3  = P1V8_MCP_CPU1
  IOF4  = GND
  IOF5  = CLK_322M_156M_CPU1_OSC_VRM_DN
  IOF6  = GND
  IOF7  = GND
  IOF8  = GND
  IOF9  = GND
  IOF10  = GND
  IOF11  = GND
  IOF12  = GND
  IOF13  = GND
  IOF14  = GND
  IOF15  = GND
  IOF16  = GND
  IOF17  = GND
  IOF18  = GND
  IOF19  = GND
  IOF20  = GND

(kicad_pcb
	(version 20260206)
	(generator "pcbnew")
	(generator_version "10.0")
	(general
		(thickness 1.6)
		(legacy_teardrops no)
	)
	(paper "A4")
	(title_block
		(title "Wiwynn_Tioga_Pass_MB.brd")
		(comment 1 "Tioga Pass / footprint 1695 of 4770 (J4E1), pads 1-49 of 122")
	)
	(layers
		(0 "F.Cu" signal "TOP")
		(4 "In1.Cu" signal "L2GND")
		(6 "In2.Cu" signal "L3")
		(8 "In3.Cu" signal "L4GND")
		(10 "In4.Cu" signal "L5")
		(12 "In5.Cu" signal "L6GND")
		(14 "In6.Cu" signal "L7VCC")
		(16 "In7.Cu" signal "L8VCC")
		(18 "In8.Cu" signal "L9GND")
		(20 "In9.Cu" signal "L10")
		(22 "In10.Cu" signal "L11GND")
		(24 "In11.Cu" signal "L12")
		(26 "In12.Cu" signal "L13GND")
		(2 "B.Cu" signal "BOTTOM")
		(9 "F.Adhes" user "F.Adhesive")
		(11 "B.Adhes" user "B.Adhesive")
		(13 "F.Paste" user "Package Geometry/Pastemask Top")
		(15 "B.Paste" user "Package Geometry/Pastemask Bottom")
		(5 "F.SilkS" user "Ref Des/Silkscreen Top")
		(7 "B.SilkS" user "Ref Des/Silkscreen Bottom")
		(1 "F.Mask" user "Board Geometry/Soldermask Top")
		(3 "B.Mask" user "Board Geometry/Soldermask Bottom")
		(17 "Dwgs.User" user "User.Drawings")
		(19 "Cmts.User" user "User.Comments")
		(21 "Eco1.User" user "User.Eco1")
		(23 "Eco2.User" user "User.Eco2")
		(25 "Edge.Cuts" user "Board Geometry/Outline")
		(27 "Margin" user)
		(31 "F.CrtYd" user "Package Geometry/Place Bound Top")
		(29 "B.CrtYd" user "Package Geometry/Place Bound Bottom")
		(35 "F.Fab" user "Ref Des/Assembly Top")
		(33 "B.Fab" user "Ref Des/Assembly Bottom")
	)
	(footprint ""
		(layer "F.Cu")
		(at 164.615114 -43.80103 90)
		(property "Reference" "J4E1"
			(at -3.59283 -5.018024 90)
			(unlocked yes)
			(layer "F.SilkS")
			(effects
				(font
					(size 0.7874 0.5842)
					(thickness 0.1524)
				)
			)
		)
		(property "Value" ""
			(at 0 0 90)
			(layer "F.Fab")
			(effects
				(font
					(size 1.27 1.27)
				)
			)
		)
		(duplicate_pad_numbers_are_jumpers no)
		(pad "" np_thru_hole circle
			(at -3.175 26.5557 90)
			(size 0.254 0.254)
			(drill 1.27)
			(layers "*.Cu" "*.Mask")
			(clearance 0.8255)
			(thermal_gap 0.8255)
		)
		(pad "" np_thru_hole circle
			(at -0.127 -2.4257 90)
			(size 0.254 0.254)
			(drill 1.27)
			(layers "*.Cu" "*.Mask")
			(clearance 0.8255)
			(thermal_gap 0.8255)
		)
		(pad "A1" smd circle
			(at 0 0 90)
			(size 0.635 0.635)
			(layers "F.Cu" "F.Mask" "F.Paste")
			(net "PVCCMCP_CPU1")
		)
		(pad "A2" smd circle
			(at 0 1.27 90)
			(size 0.635 0.635)
			(layers "F.Cu" "F.Mask" "F.Paste")
			(net "PVCCMCP_CPU1")
		)
		(pad "A3" smd circle
			(at 0 2.54 90)
			(size 0.635 0.635)
			(layers "F.Cu" "F.Mask" "F.Paste")
			(net "PVCCMCP_CPU1")
		)
		(pad "A4" smd circle
			(at 0 3.81 90)
			(size 0.635 0.635)
			(layers "F.Cu" "F.Mask" "F.Paste")
			(net "VSENSE_PVCCMCP_CPU1_SKT_VSEN")
		)
		(pad "A5" smd circle
			(at 0 5.08 90)
			(size 0.635 0.635)
			(layers "F.Cu" "F.Mask" "F.Paste")
			(net "PVCCMCP_CPU1")
		)
		(pad "A6" smd circle
			(at 0 6.35 90)
			(size 0.635 0.635)
			(layers "F.Cu" "F.Mask" "F.Paste")
			(net "PVCCMCP_CPU1")
		)
		(pad "A7" smd circle
			(at 0 7.62 90)
			(size 0.635 0.635)
			(layers "F.Cu" "F.Mask" "F.Paste")
			(net "PVCCMCP_CPU1")
		)
		(pad "A8" smd circle
			(at 0 8.89 90)
			(size 0.635 0.635)
			(layers "F.Cu" "F.Mask" "F.Paste")
			(net "PVCCMCP_CPU1")
		)
		(pad "A9" smd circle
			(at 0 10.16 90)
			(size 0.635 0.635)
			(layers "F.Cu" "F.Mask" "F.Paste")
			(net "PVCCMCP_CPU1")
		)
		(pad "A10" smd circle
			(at 0 11.43 90)
			(size 0.635 0.635)
			(layers "F.Cu" "F.Mask" "F.Paste")
			(net "PVCCMCP_CPU1")
		)
		(pad "A11" smd circle
			(at 0 12.7 90)
			(size 0.635 0.635)
			(layers "F.Cu" "F.Mask" "F.Paste")
			(net "PVCCMCP_CPU1")
		)
		(pad "A12" smd circle
			(at 0 13.97 90)
			(size 0.635 0.635)
			(layers "F.Cu" "F.Mask" "F.Paste")
			(net "PVCCMCP_CPU1")
		)
		(pad "A13" smd circle
			(at 0 15.24 90)
			(size 0.635 0.635)
			(layers "F.Cu" "F.Mask" "F.Paste")
			(net "PVCCMCP_CPU1")
		)
		(pad "A14" smd circle
			(at 0 16.51 90)
			(size 0.635 0.635)
			(layers "F.Cu" "F.Mask" "F.Paste")
			(net "PVCCMCP_CPU1")
		)
		(pad "A15" smd circle
			(at 0 17.78 90)
			(size 0.635 0.635)
			(layers "F.Cu" "F.Mask" "F.Paste")
			(net "PVCCMCP_CPU1")
		)
		(pad "A16" smd circle
			(at 0 19.05 90)
			(size 0.635 0.635)
			(layers "F.Cu" "F.Mask" "F.Paste")
			(net "PVCCMCP_CPU1")
		)
		(pad "A17" smd circle
			(at 0 20.32 90)
			(size 0.635 0.635)
			(layers "F.Cu" "F.Mask" "F.Paste")
			(net "PVCCMCP_CPU1")
		)
		(pad "A18" smd circle
			(at 0 21.59 90)
			(size 0.635 0.635)
			(layers "F.Cu" "F.Mask" "F.Paste")
			(net "PVCCMCP_CPU1")
		)
		(pad "A19" smd circle
			(at 0 22.86 90)
			(size 0.635 0.635)
			(layers "F.Cu" "F.Mask" "F.Paste")
			(net "GND")
		)
		(pad "A20" smd circle
			(at 0 24.13 90)
			(size 0.635 0.635)
			(layers "F.Cu" "F.Mask" "F.Paste")
			(net "GND")
		)
		(pad "B1" smd circle
			(at -1.27 0 90)
			(size 0.635 0.635)
			(layers "F.Cu" "F.Mask" "F.Paste")
			(net "PVCCMCP_CPU1")
		)
		(pad "B2" smd circle
			(at -1.27 1.27 90)
			(size 0.635 0.635)
			(layers "F.Cu" "F.Mask" "F.Paste")
			(net "PVCCMCP_CPU1")
		)
		(pad "B3" smd circle
			(at -1.27 2.54 90)
			(size 0.635 0.635)
			(layers "F.Cu" "F.Mask" "F.Paste")
			(net "PVCCMCP_CPU1")
		)
		(pad "B4" smd circle
			(at -1.27 3.81 90)
			(size 0.635 0.635)
			(layers "F.Cu" "F.Mask" "F.Paste")
			(net "VSENSE_PVCCMCP_CPU1_SKT_VRTN")
		)
		(pad "B5" smd circle
			(at -1.27 5.08 90)
			(size 0.635 0.635)
			(layers "F.Cu" "F.Mask" "F.Paste")
			(net "PVCCMCP_CPU1")
		)
		(pad "B6" smd circle
			(at -1.27 6.35 90)
			(size 0.635 0.635)
			(layers "F.Cu" "F.Mask" "F.Paste")
			(net "PVCCMCP_CPU1")
		)
		(pad "B7" smd circle
			(at -1.27 7.62 90)
			(size 0.635 0.635)
			(layers "F.Cu" "F.Mask" "F.Paste")
			(net "PVCCMCP_CPU1")
		)
		(pad "B8" smd circle
			(at -1.27 8.89 90)
			(size 0.635 0.635)
			(layers "F.Cu" "F.Mask" "F.Paste")
			(net "PVCCMCP_CPU1")
		)
		(pad "B9" smd circle
			(at -1.27 10.16 90)
			(size 0.635 0.635)
			(layers "F.Cu" "F.Mask" "F.Paste")
			(net "PVCCMCP_CPU1")
		)
		(pad "B10" smd circle
			(at -1.27 11.43 90)
			(size 0.635 0.635)
			(layers "F.Cu" "F.Mask" "F.Paste")
			(net "PVCCMCP_CPU1")
		)
		(pad "B11" smd circle
			(at -1.27 12.7 90)
			(size 0.635 0.635)
			(layers "F.Cu" "F.Mask" "F.Paste")
			(net "PVCCMCP_CPU1")
		)
		(pad "B12" smd circle
			(at -1.27 13.97 90)
			(size 0.635 0.635)
			(layers "F.Cu" "F.Mask" "F.Paste")
			(net "PVCCMCP_CPU1")
		)
		(pad "B13" smd circle
			(at -1.27 15.24 90)
			(size 0.635 0.635)
			(layers "F.Cu" "F.Mask" "F.Paste")
			(net "PVCCMCP_CPU1")
		)
		(pad "B14" smd circle
			(at -1.27 16.51 90)
			(size 0.635 0.635)
			(layers "F.Cu" "F.Mask" "F.Paste")
			(net "PVCCMCP_CPU1")
		)
		(pad "B15" smd circle
			(at -1.27 17.78 90)
			(size 0.635 0.635)
			(layers "F.Cu" "F.Mask" "F.Paste")
			(net "PVCCMCP_CPU1")
		)
		(pad "B16" smd circle
			(at -1.27 19.05 90)
			(size 0.635 0.635)
			(layers "F.Cu" "F.Mask" "F.Paste")
			(net "PVCCMCP_CPU1")
		)
		(pad "B17" smd circle
			(at -1.27 20.32 90)
			(size 0.635 0.635)
			(layers "F.Cu" "F.Mask" "F.Paste")
			(net "PVCCMCP_CPU1")
		)
		(pad "B18" smd circle
			(at -1.27 21.59 90)
			(size 0.635 0.635)
			(layers "F.Cu" "F.Mask" "F.Paste")
			(net "PVCCMCP_CPU1")
		)
		(pad "B19" smd circle
			(at -1.27 22.86 90)
			(size 0.635 0.635)
			(layers "F.Cu" "F.Mask" "F.Paste")
			(net "GND")
		)
		(pad "B20" smd circle
			(at -1.27 24.13 90)
			(size 0.635 0.635)
			(layers "F.Cu" "F.Mask" "F.Paste")
			(net "GND")
		)
		(pad "C1" smd circle
			(at -2.54 0 90)
			(size 0.635 0.635)
			(layers "F.Cu" "F.Mask" "F.Paste")
			(net "PVCCMCP_CPU1")
		)
		(pad "C2" smd circle
			(at -2.54 1.27 90)
			(size 0.635 0.635)
			(layers "F.Cu" "F.Mask" "F.Paste")
			(net "PVCCMCP_CPU1")
		)
		(pad "C3" smd circle
			(at -2.54 2.54 90)
			(size 0.635 0.635)
			(layers "F.Cu" "F.Mask" "F.Paste")
			(net "PVCCMCP_CPU1")
		)
		(pad "C4" smd circle
			(at -2.54 3.81 90)
			(size 0.635 0.635)
			(layers "F.Cu" "F.Mask" "F.Paste")
			(net "PVCCMCP_CPU1")
		)
		(pad "C5" smd circle
			(at -2.54 5.08 90)
			(size 0.635 0.635)
			(layers "F.Cu" "F.Mask" "F.Paste")
			(net "PVCCMCP_CPU1")
		)
		(pad "C6" smd circle
			(at -2.54 6.35 90)
			(size 0.635 0.635)
			(layers "F.Cu" "F.Mask" "F.Paste")
			(net "PVCCMCP_CPU1")
		)
		(pad "C7" smd circle
			(at -2.54 7.62 90)
			(size 0.635 0.635)
			(layers "F.Cu" "F.Mask" "F.Paste")
			(net "PVCCMCP_CPU1")
		)
	)
)
